(kicad_pcb
	(version 20260206)
	(generator "pcbnew")
	(generator_version "10.0")
	(general
		(thickness 1.6)
		(legacy_teardrops no)
	)
	(paper "A4")
	(title_block
		(title "01162023_DA0F0TEBIF0_F0T_Expander_BD_F_brd_V02_OCP.brd")
		(comment 1 "Grand Teton / footprints 2326-2334 of 9728")
	)
	(layers
		(0 "F.Cu" signal "TOP")
		(4 "In1.Cu" signal "GND")
		(6 "In2.Cu" signal "VCC")
		(8 "In3.Cu" signal "VCC1")
		(10 "In4.Cu" signal "GND1")
		(12 "In5.Cu" signal "IN1")
		(14 "In6.Cu" signal "GND2")
		(16 "In7.Cu" signal "IN2")
		(18 "In8.Cu" signal "GND3")
		(20 "In9.Cu" signal "IN3")
		(22 "In10.Cu" signal "GND4")
		(24 "In11.Cu" signal "IN4")
		(26 "In12.Cu" signal "GND5")
		(28 "In13.Cu" signal "IN5")
		(30 "In14.Cu" signal "GND6")
		(32 "In15.Cu" signal "IN6")
		(34 "In16.Cu" signal "GND7")
		(2 "B.Cu" signal "BOTTOM")
		(9 "F.Adhes" user "F.Adhesive")
		(11 "B.Adhes" user "B.Adhesive")
		(13 "F.Paste" user "Package Geometry/Pastemask Top")
		(15 "B.Paste" user "Package Geometry/Pastemask Bottom")
		(5 "F.SilkS" user "Ref Des/Silkscreen Top")
		(7 "B.SilkS" user "Ref Des/Silkscreen Bottom")
		(1 "F.Mask" user "Board Geometry/Soldermask Top")
		(3 "B.Mask" user "Board Geometry/Soldermask Bottom")
		(17 "Dwgs.User" user "User.Drawings")
		(19 "Cmts.User" user "User.Comments")
		(21 "Eco1.User" user "User.Eco1")
		(23 "Eco2.User" user "User.Eco2")
		(25 "Edge.Cuts" user "Board Geometry/Outline")
		(27 "Margin" user)
		(31 "F.CrtYd" user "Package Geometry/Place Bound Top")
		(29 "B.CrtYd" user "Package Geometry/Place Bound Bottom")
		(35 "F.Fab" user "Ref Des/Assembly Top")
		(33 "B.Fab" user "Ref Des/Assembly Bottom")
	)
	(footprint ""
		(layer "F.Cu")
		(at 51.61153 -71.458074 -90)
		(property "Reference" "PD88"
			(at 4.198874 -2.79654 90)
			(unlocked yes)
			(layer "F.SilkS")
			(effects
				(font
					(size 0.7874 0.5842)
					(thickness 0.1524)
				)
				(justify left)
			)
		)
		(property "Value" ""
			(at 0 0 270)
			(layer "F.Fab")
			(effects
				(font
					(size 1.27 1.27)
				)
			)
		)
		(duplicate_pad_numbers_are_jumpers no)
		(fp_line
			(start -3.656584 1.970024)
			(end 4.240784 1.970024)
			(stroke
				(width 0.1524)
				(type default)
			)
			(layer "F.SilkS")
		)
		(fp_line
			(start 4.240784 1.970024)
			(end 4.240784 -1.970024)
			(stroke
				(width 0.1524)
				(type default)
			)
			(layer "F.SilkS")
		)
		(fp_line
			(start -3.656584 -1.970024)
			(end -3.656584 1.970024)
			(stroke
				(width 0.1524)
				(type default)
			)
			(layer "F.SilkS")
		)
		(fp_line
			(start 4.240784 -1.970024)
			(end -3.656584 -1.970024)
			(stroke
				(width 0.1524)
				(type default)
			)
			(layer "F.SilkS")
		)
		(fp_poly
			(pts
				(xy 3.580384 1.970024) (xy 3.580384 -1.970024) (xy 4.240784 -1.970024) (xy 4.240784 1.970024)
			)
			(stroke
				(width 0)
				(type default)
			)
			(fill yes)
			(layer "F.SilkS")
		)
		(fp_line
			(start -2.3749 1.970024)
			(end 2.3749 1.970024)
			(stroke
				(width 0.1)
				(type default)
			)
			(layer "F.Fab")
		)
		(fp_line
			(start 2.3749 1.970024)
			(end 2.3749 -1.970024)
			(stroke
				(width 0.1)
				(type default)
			)
			(layer "F.Fab")
		)
		(fp_line
			(start -2.3749 -1.970024)
			(end -2.3749 1.970024)
			(stroke
				(width 0.1)
				(type default)
			)
			(layer "F.Fab")
		)
		(fp_line
			(start 2.3749 -1.970024)
			(end -2.3749 -1.970024)
			(stroke
				(width 0.1)
				(type default)
			)
			(layer "F.Fab")
		)
		(fp_text user "+"
			(at -4.9784 -0.23495 270)
			(unlocked yes)
			(layer "F.Fab")
			(effects
				(font
					(size 1.905 1.4224)
					(thickness 0.1524)
				)
				(justify left)
			)
		)
		(fp_text user "-"
			(at 4.1656 -0.23495 270)
			(unlocked yes)
			(layer "F.Fab")
			(effects
				(font
					(size 1.905 1.4224)
					(thickness 0.1524)
				)
				(justify left)
			)
		)
		(pad "A" smd rect
			(at -2.450084 0 270)
			(size 2.159 2.2606)
			(layers "F.Cu" "F.Mask" "F.Paste")
			(net "GND")
		)
		(pad "C" smd rect
			(at 2.450084 0 270)
			(size 2.159 2.2606)
			(layers "F.Cu" "F.Mask" "F.Paste")
			(net "P12V_AUX")
		)
	)
	(footprint ""
		(layer "F.Cu")
		(at 411.97784 -115.283742 180)
		(property "Reference" "R394"
			(at 0 0 180)
			(layer "F.SilkS")
			(hide yes)
			(effects
				(font
					(size 1.27 1.27)
				)
			)
		)
		(property "Value" ""
			(at 0 0 180)
			(layer "F.Fab")
			(effects
				(font
					(size 1.27 1.27)
				)
			)
		)
		(duplicate_pad_numbers_are_jumpers no)
		(fp_line
			(start 0.7874 0.4064)
			(end -0.7874 0.4064)
			(stroke
				(width 0.1524)
				(type default)
			)
			(layer "F.SilkS")
		)
		(fp_line
			(start 0.7874 -0.4064)
			(end 0.7874 0.4064)
			(stroke
				(width 0.1524)
				(type default)
			)
			(layer "F.SilkS")
		)
		(fp_line
			(start -0.7874 0.4064)
			(end -0.7874 -0.4064)
			(stroke
				(width 0.1524)
				(type default)
			)
			(layer "F.SilkS")
		)
		(fp_line
			(start -0.7874 -0.4064)
			(end 0.7874 -0.4064)
			(stroke
				(width 0.1524)
				(type default)
			)
			(layer "F.SilkS")
		)
		(fp_line
			(start 0.67945 0.3048)
			(end 0.120396 0.3048)
			(stroke
				(width 0.1)
				(type default)
			)
			(layer "F.Fab")
		)
		(fp_line
			(start 0.67945 -0.3048)
			(end 0.67945 0.3048)
			(stroke
				(width 0.1)
				(type default)
			)
			(layer "F.Fab")
		)
		(fp_line
			(start 0.12065 -0.2794)
			(end 0.12065 -0.3048)
			(stroke
				(width 0.1)
				(type default)
			)
			(layer "F.Fab")
		)
		(fp_line
			(start 0.12065 -0.3048)
			(end 0.67945 -0.3048)
			(stroke
				(width 0.1)
				(type default)
			)
			(layer "F.Fab")
		)
		(fp_line
			(start 0.120396 0.3048)
			(end 0.120396 0.2794)
			(stroke
				(width 0.1)
				(type default)
			)
			(layer "F.Fab")
		)
		(fp_line
			(start 0.120396 0.2794)
			(end -0.12065 0.2794)
			(stroke
				(width 0.1)
				(type default)
			)
			(layer "F.Fab")
		)
		(fp_line
			(start -0.12065 0.3048)
			(end -0.67945 0.3048)
			(stroke
				(width 0.1)
				(type default)
			)
			(layer "F.Fab")
		)
		(fp_line
			(start -0.12065 0.2794)
			(end -0.12065 0.3048)
			(stroke
				(width 0.1)
				(type default)
			)
			(layer "F.Fab")
		)
		(fp_line
			(start -0.12065 -0.2794)
			(end 0.12065 -0.2794)
			(stroke
				(width 0.1)
				(type default)
			)
			(layer "F.Fab")
		)
		(fp_line
			(start -0.12065 -0.305054)
			(end -0.12065 -0.2794)
			(stroke
				(width 0.1)
				(type default)
			)
			(layer "F.Fab")
		)
		(fp_line
			(start -0.67945 0.3048)
			(end -0.67945 -0.305054)
			(stroke
				(width 0.1)
				(type default)
			)
			(layer "F.Fab")
		)
		(fp_line
			(start -0.67945 -0.305054)
			(end -0.12065 -0.305054)
			(stroke
				(width 0.1)
				(type default)
			)
			(layer "F.Fab")
		)
		(pad "1" smd circle
			(at -0.40005 0 180)
			(size 0 0)
			(layers "F.Cu" "F.Mask" "F.Paste")
			(net "RST_SMB_NIC7_MUX_ISO_R_N")
		)
		(pad "2" smd circle
			(at 0.40005 0 180)
			(size 0 0)
			(layers "F.Cu" "F.Mask" "F.Paste")
			(net "RST_SMB_NIC7_MUX_ISO_N")
		)
	)
	(footprint ""
		(layer "F.Cu")
		(at 8.362696 -169.492676 180)
		(property "Reference" "PC20"
			(at 0 0 180)
			(layer "F.SilkS")
			(hide yes)
			(effects
				(font
					(size 1.27 1.27)
				)
			)
		)
		(property "Value" ""
			(at 0 0 180)
			(layer "F.Fab")
			(effects
				(font
					(size 1.27 1.27)
				)
			)
		)
		(duplicate_pad_numbers_are_jumpers no)
		(fp_line
			(start 1.524 0.762)
			(end -1.524 0.762)
			(stroke
				(width 0.1524)
				(type default)
			)
			(layer "F.SilkS")
		)
		(fp_line
			(start 1.524 -0.762)
			(end 1.524 0.762)
			(stroke
				(width 0.1524)
				(type default)
			)
			(layer "F.SilkS")
		)
		(fp_line
			(start -1.524 0.762)
			(end -1.524 -0.762)
			(stroke
				(width 0.1524)
				(type default)
			)
			(layer "F.SilkS")
		)
		(fp_line
			(start -1.524 -0.762)
			(end 1.524 -0.762)
			(stroke
				(width 0.1524)
				(type default)
			)
			(layer "F.SilkS")
		)
		(fp_line
			(start 1.1049 0.724916)
			(end 1.1049 -0.724916)
			(stroke
				(width 0.1)
				(type default)
			)
			(layer "F.Fab")
		)
		(fp_line
			(start 1.1049 -0.724916)
			(end -1.1049 -0.724916)
			(stroke
				(width 0.1)
				(type default)
			)
			(layer "F.Fab")
		)
		(fp_line
			(start -1.1049 0.724916)
			(end 1.1049 0.724916)
			(stroke
				(width 0.1)
				(type default)
			)
			(layer "F.Fab")
		)
		(fp_line
			(start -1.1049 -0.724916)
			(end -1.1049 0.724916)
			(stroke
				(width 0.1)
				(type default)
			)
			(layer "F.Fab")
		)
		(pad "1" smd rect
			(at -0.889 0)
			(size 1.016 1.27)
			(layers "F.Cu" "F.Mask" "F.Paste")
			(net "P5V_AUX")
		)
		(pad "2" smd rect
			(at 0.889 0)
			(size 1.016 1.27)
			(layers "F.Cu" "F.Mask" "F.Paste")
			(net "GND")
		)
	)
	(footprint ""
		(layer "F.Cu")
		(at 80.657446 -107.552998 -90)
		(property "Reference" "C860"
			(at 0 0 270)
			(layer "F.SilkS")
			(hide yes)
			(effects
				(font
					(size 1.27 1.27)
				)
			)
		)
		(property "Value" ""
			(at 0 0 270)
			(layer "F.Fab")
			(effects
				(font
					(size 1.27 1.27)
				)
			)
		)
		(duplicate_pad_numbers_are_jumpers no)
		(fp_line
			(start -1.524 0.762)
			(end -1.524 -0.762)
			(stroke
				(width 0.1524)
				(type default)
			)
			(layer "F.SilkS")
		)
		(fp_line
			(start 1.524 0.762)
			(end -1.524 0.762)
			(stroke
				(width 0.1524)
				(type default)
			)
			(layer "F.SilkS")
		)
		(fp_line
			(start -1.524 -0.762)
			(end 1.524 -0.762)
			(stroke
				(width 0.1524)
				(type default)
			)
			(layer "F.SilkS")
		)
		(fp_line
			(start 1.524 -0.762)
			(end 1.524 0.762)
			(stroke
				(width 0.1524)
				(type default)
			)
			(layer "F.SilkS")
		)
		(fp_line
			(start -1.1049 0.724916)
			(end 1.1049 0.724916)
			(stroke
				(width 0.1)
				(type default)
			)
			(layer "F.Fab")
		)
		(fp_line
			(start 1.1049 0.724916)
			(end 1.1049 -0.724916)
			(stroke
				(width 0.1)
				(type default)
			)
			(layer "F.Fab")
		)
		(fp_line
			(start -1.1049 -0.724916)
			(end -1.1049 0.724916)
			(stroke
				(width 0.1)
				(type default)
			)
			(layer "F.Fab")
		)
		(fp_line
			(start 1.1049 -0.724916)
			(end -1.1049 -0.724916)
			(stroke
				(width 0.1)
				(type default)
			)
			(layer "F.Fab")
		)
		(pad "1" smd rect
			(at -0.889 0 90)
			(size 1.016 1.27)
			(layers "F.Cu" "F.Mask" "F.Paste")
			(net "P12V_NIC1")
		)
		(pad "2" smd rect
			(at 0.889 0 90)
			(size 1.016 1.27)
			(layers "F.Cu" "F.Mask" "F.Paste")
			(net "GND")
		)
	)
	(footprint ""
		(layer "F.Cu")
		(at 99.149916 -289.820096)
		(property "Reference" "H136"
			(at -2.35966 5.20065 0)
			(unlocked yes)
			(layer "F.SilkS")
			(effects
				(font
					(size 0.7874 0.5842)
					(thickness 0.1524)
				)
				(justify left)
			)
		)
		(property "Value" ""
			(at 0 0 0)
			(layer "F.Fab")
			(effects
				(font
					(size 1.27 1.27)
				)
			)
		)
		(duplicate_pad_numbers_are_jumpers no)
		(pad "1" thru_hole circle
			(at 0 0)
			(size 6.5024 6.5024)
			(drill 3.2004)
			(layers "*.Cu" "*.Mask")
			(remove_unused_layers no)
			(net "GND")
			(clearance -1.397)
		)
	)
	(footprint ""
		(layer "F.Cu")
		(at 374.543828 -48.93691 180)
		(property "Reference" "R644"
			(at 0 0 180)
			(layer "F.SilkS")
			(hide yes)
			(effects
				(font
					(size 1.27 1.27)
				)
			)
		)
		(property "Value" ""
			(at 0 0 180)
			(layer "F.Fab")
			(effects
				(font
					(size 1.27 1.27)
				)
			)
		)
		(duplicate_pad_numbers_are_jumpers no)
		(fp_line
			(start 0.7874 0.4064)
			(end -0.7874 0.4064)
			(stroke
				(width 0.1524)
				(type default)
			)
			(layer "F.SilkS")
		)
		(fp_line
			(start 0.7874 -0.4064)
			(end 0.7874 0.4064)
			(stroke
				(width 0.1524)
				(type default)
			)
			(layer "F.SilkS")
		)
		(fp_line
			(start -0.7874 0.4064)
			(end -0.7874 -0.4064)
			(stroke
				(width 0.1524)
				(type default)
			)
			(layer "F.SilkS")
		)
		(fp_line
			(start -0.7874 -0.4064)
			(end 0.7874 -0.4064)
			(stroke
				(width 0.1524)
				(type default)
			)
			(layer "F.SilkS")
		)
		(fp_line
			(start 0.67945 0.3048)
			(end 0.120396 0.3048)
			(stroke
				(width 0.1)
				(type default)
			)
			(layer "F.Fab")
		)
		(fp_line
			(start 0.67945 -0.3048)
			(end 0.67945 0.3048)
			(stroke
				(width 0.1)
				(type default)
			)
			(layer "F.Fab")
		)
		(fp_line
			(start 0.12065 -0.2794)
			(end 0.12065 -0.3048)
			(stroke
				(width 0.1)
				(type default)
			)
			(layer "F.Fab")
		)
		(fp_line
			(start 0.12065 -0.3048)
			(end 0.67945 -0.3048)
			(stroke
				(width 0.1)
				(type default)
			)
			(layer "F.Fab")
		)
		(fp_line
			(start 0.120396 0.3048)
			(end 0.120396 0.2794)
			(stroke
				(width 0.1)
				(type default)
			)
			(layer "F.Fab")
		)
		(fp_line
			(start 0.120396 0.2794)
			(end -0.12065 0.2794)
			(stroke
				(width 0.1)
				(type default)
			)
			(layer "F.Fab")
		)
		(fp_line
			(start -0.12065 0.3048)
			(end -0.67945 0.3048)
			(stroke
				(width 0.1)
				(type default)
			)
			(layer "F.Fab")
		)
		(fp_line
			(start -0.12065 0.2794)
			(end -0.12065 0.3048)
			(stroke
				(width 0.1)
				(type default)
			)
			(layer "F.Fab")
		)
		(fp_line
			(start -0.12065 -0.2794)
			(end 0.12065 -0.2794)
			(stroke
				(width 0.1)
				(type default)
			)
			(layer "F.Fab")
		)
		(fp_line
			(start -0.12065 -0.305054)
			(end -0.12065 -0.2794)
			(stroke
				(width 0.1)
				(type default)
			)
			(layer "F.Fab")
		)
		(fp_line
			(start -0.67945 0.3048)
			(end -0.67945 -0.305054)
			(stroke
				(width 0.1)
				(type default)
			)
			(layer "F.Fab")
		)
		(fp_line
			(start -0.67945 -0.305054)
			(end -0.12065 -0.305054)
			(stroke
				(width 0.1)
				(type default)
			)
			(layer "F.Fab")
		)
		(pad "1" smd circle
			(at -0.40005 0 180)
			(size 0 0)
			(layers "F.Cu" "F.Mask" "F.Paste")
			(net "SMB_BIC_I2C6_MUX_SSD_8_15_ADC_R_SDA")
		)
		(pad "2" smd circle
			(at 0.40005 0 180)
			(size 0 0)
			(layers "F.Cu" "F.Mask" "F.Paste")
			(net "SMB_SSD12_ADC_SDA")
		)
	)
	(footprint ""
		(layer "F.Cu")
		(at 451.298056 -266.996672 180)
		(property "Reference" "R6140"
			(at 0 0 180)
			(layer "F.SilkS")
			(hide yes)
			(effects
				(font
					(size 1.27 1.27)
				)
			)
		)
		(property "Value" ""
			(at 0 0 180)
			(layer "F.Fab")
			(effects
				(font
					(size 1.27 1.27)
				)
			)
		)
		(duplicate_pad_numbers_are_jumpers no)
		(fp_line
			(start 2.576322 1.1303)
			(end -2.576322 1.1303)
			(stroke
				(width 0.1524)
				(type default)
			)
			(layer "F.SilkS")
		)
		(fp_line
			(start 2.576322 -1.1303)
			(end 2.576322 1.1303)
			(stroke
				(width 0.1524)
				(type default)
			)
			(layer "F.SilkS")
		)
		(fp_line
			(start -2.576322 1.1303)
			(end -2.576322 -1.1303)
			(stroke
				(width 0.1524)
				(type default)
			)
			(layer "F.SilkS")
		)
		(fp_line
			(start -2.576322 -1.1303)
			(end 2.576322 -1.1303)
			(stroke
				(width 0.1524)
				(type default)
			)
			(layer "F.SilkS")
		)
		(fp_line
			(start 1.649984 0.899922)
			(end 1.649984 -0.899922)
			(stroke
				(width 0.1)
				(type default)
			)
			(layer "F.Fab")
		)
		(fp_line
			(start 1.649984 -0.899922)
			(end -1.649984 -0.899922)
			(stroke
				(width 0.1)
				(type default)
			)
			(layer "F.Fab")
		)
		(fp_line
			(start -1.649984 0.899922)
			(end 1.649984 0.899922)
			(stroke
				(width 0.1)
				(type default)
			)
			(layer "F.Fab")
		)
		(fp_line
			(start -1.649984 -0.899922)
			(end -1.649984 0.899922)
			(stroke
				(width 0.1)
				(type default)
			)
			(layer "F.Fab")
		)
		(pad "1A" smd rect
			(at -1.700022 0 180)
			(size 1.4986 2.0066)
			(layers "F.Cu" "F.Mask" "F.Paste")
			(net "P1V25_PEX3")
		)
		(pad "1B" smd rect
			(at -1.077722 0 180)
			(size 0.254 0.508)
			(layers "F.Cu" "F.Mask" "F.Paste")
			(net "P1V25_PEX3")
		)
		(pad "2A" smd rect
			(at 1.700022 0 180)
			(size 1.4986 2.0066)
			(layers "F.Cu" "F.Mask" "F.Paste")
			(net "P1V25_SERDES_VDDPLL_PEX3")
		)
		(pad "2B" smd rect
			(at 1.077722 0 180)
			(size 0.254 0.508)
			(layers "F.Cu" "F.Mask" "F.Paste")
			(net "P1V25_SERDES_VDDPLL_PEX3")
		)
	)
	(footprint ""
		(layer "F.Cu")
		(at 80.019398 -143.504666 180)
		(property "Reference" "C15"
			(at 0 0 180)
			(layer "F.SilkS")
			(hide yes)
			(effects
				(font
					(size 1.27 1.27)
				)
			)
		)
		(property "Value" ""
			(at 0 0 180)
			(layer "F.Fab")
			(effects
				(font
					(size 1.27 1.27)
				)
			)
		)
		(duplicate_pad_numbers_are_jumpers no)
		(fp_line
			(start 0.299974 0.150114)
			(end -0.299974 0.150114)
			(stroke
				(width 0.1)
				(type default)
			)
			(layer "F.Fab")
		)
		(fp_line
			(start 0.299974 -0.150114)
			(end 0.299974 0.150114)
			(stroke
				(width 0.1)
				(type default)
			)
			(layer "F.Fab")
		)
		(fp_line
			(start -0.299974 0.150114)
			(end -0.299974 -0.150114)
			(stroke
				(width 0.1)
				(type default)
			)
			(layer "F.Fab")
		)
		(fp_line
			(start -0.299974 -0.150114)
			(end 0.299974 -0.150114)
			(stroke
				(width 0.1)
				(type default)
			)
			(layer "F.Fab")
		)
		(pad "1" smd rect
			(at -0.2667 0 180)
			(size 0.3048 0.381)
			(layers "F.Cu" "F.Mask" "F.Paste")
			(net "P5E_PEX0_STN0_TX_DP<8>")
		)
		(pad "2" smd rect
			(at 0.2667 0 180)
			(size 0.3048 0.381)
			(layers "F.Cu" "F.Mask" "F.Paste")
			(net "P5E_PEX0_STN0_TX_C_DP<8>")
		)
	)
	(footprint ""
		(layer "F.Cu")
		(at 207.915002 -188.595508)
		(property "Reference" "R4232"
			(at 0 0 0)
			(layer "F.SilkS")
			(hide yes)
			(effects
				(font
					(size 1.27 1.27)
				)
			)
		)
		(property "Value" ""
			(at 0 0 0)
			(layer "F.Fab")
			(effects
				(font
					(size 1.27 1.27)
				)
			)
		)
		(duplicate_pad_numbers_are_jumpers no)
		(fp_line
			(start -0.7874 -0.4064)
			(end 0.7874 -0.4064)
			(stroke
				(width 0.1524)
				(type default)
			)
			(layer "F.SilkS")
		)
		(fp_line
			(start -0.7874 0.4064)
			(end -0.7874 -0.4064)
			(stroke
				(width 0.1524)
				(type default)
			)
			(layer "F.SilkS")
		)
		(fp_line
			(start 0.7874 -0.4064)
			(end 0.7874 0.4064)
			(stroke
				(width 0.1524)
				(type default)
			)
			(layer "F.SilkS")
		)
		(fp_line
			(start 0.7874 0.4064)
			(end -0.7874 0.4064)
			(stroke
				(width 0.1524)
				(type default)
			)
			(layer "F.SilkS")
		)
		(fp_line
			(start -0.67945 -0.305054)
			(end -0.12065 -0.305054)
			(stroke
				(width 0.1)
				(type default)
			)
			(layer "F.Fab")
		)
		(fp_line
			(start -0.67945 0.3048)
			(end -0.67945 -0.305054)
			(stroke
				(width 0.1)
				(type default)
			)
			(layer "F.Fab")
		)
		(fp_line
			(start -0.12065 -0.305054)
			(end -0.12065 -0.2794)
			(stroke
				(width 0.1)
				(type default)
			)
			(layer "F.Fab")
		)
		(fp_line
			(start -0.12065 -0.2794)
			(end 0.12065 -0.2794)
			(stroke
				(width 0.1)
				(type default)
			)
			(layer "F.Fab")
		)
		(fp_line
			(start -0.12065 0.2794)
			(end -0.12065 0.3048)
			(stroke
				(width 0.1)
				(type default)
			)
			(layer "F.Fab")
		)
		(fp_line
			(start -0.12065 0.3048)
			(end -0.67945 0.3048)
			(stroke
				(width 0.1)
				(type default)
			)
			(layer "F.Fab")
		)
		(fp_line
			(start 0.120396 0.2794)
			(end -0.12065 0.2794)
			(stroke
				(width 0.1)
				(type default)
			)
			(layer "F.Fab")
		)
		(fp_line
			(start 0.120396 0.3048)
			(end 0.120396 0.2794)
			(stroke
				(width 0.1)
				(type default)
			)
			(layer "F.Fab")
		)
		(fp_line
			(start 0.12065 -0.3048)
			(end 0.67945 -0.3048)
			(stroke
				(width 0.1)
				(type default)
			)
			(layer "F.Fab")
		)
		(fp_line
			(start 0.12065 -0.2794)
			(end 0.12065 -0.3048)
			(stroke
				(width 0.1)
				(type default)
			)
			(layer "F.Fab")
		)
		(fp_line
			(start 0.67945 -0.3048)
			(end 0.67945 0.3048)
			(stroke
				(width 0.1)
				(type default)
			)
			(layer "F.Fab")
		)
		(fp_line
			(start 0.67945 0.3048)
			(end 0.120396 0.3048)
			(stroke
				(width 0.1)
				(type default)
			)
			(layer "F.Fab")
		)
		(pad "1" smd circle
			(at -0.40005 0)
			(size 0 0)
			(layers "F.Cu" "F.Mask" "F.Paste")
			(net "SMB_FIO_R1_SCL")
		)
		(pad "2" smd circle
			(at 0.40005 0)
			(size 0 0)
			(layers "F.Cu" "F.Mask" "F.Paste")
			(net "SMB_IO_DEBUG_CARD_R_SCL")
		)
	)
)
